# TIMECARD (Time Appliance Project (Time Card)) — schematic netlist excerpt (pin names and nets, part order shuffled) for the footprints in the layout excerpt that follows; sources: Cadence DE-HDL packaged netlist, KiCad conversion of R4006-B0001-02_R01.brd

R388  RESISTOR  33OHM 1%  pkg SMC_0402R_H016  page 26 : \1\ = SMA2_LED_BLUE_N ; \2\ = UNNAMED_14_LED4PV14_I266_1
R410  RESISTOR  4.7KOHM 1%  pkg SMC_0402R_H016  page 17 : \1\ = XP3R3V_FPGA ; \2\ = UNNAMED_6_LM75BDPTSSOP8_I81_A2

(kicad_pcb
	(version 20260206)
	(generator "pcbnew")
	(generator_version "10.0")
	(general
		(thickness 1.6)
		(legacy_teardrops no)
	)
	(paper "A4")
	(title_block
		(title "timecard-production-celestica-r4006 — R4006-B0001-02_R01.brd")
		(comment 1 "Time Appliance Project (Time Card) / footprints 104-105 of 1113")
	)
	(layers
		(0 "F.Cu" signal "TOP")
		(4 "In1.Cu" signal "L02_GND1")
		(6 "In2.Cu" signal "L03_SIG1")
		(8 "In3.Cu" signal "L04_GND2")
		(10 "In4.Cu" signal "L05_VCC1")
		(12 "In5.Cu" signal "L06_VCC2")
		(14 "In6.Cu" signal "L07_GND3")
		(16 "In7.Cu" signal "L08_SIG2")
		(18 "In8.Cu" signal "L09_GND4")
		(2 "B.Cu" signal "BOTTOM")
		(9 "F.Adhes" user "F.Adhesive")
		(11 "B.Adhes" user "B.Adhesive")
		(13 "F.Paste" user "Package Geometry/Pastemask Top")
		(15 "B.Paste" user "Package Geometry/Pastemask Bottom")
		(5 "F.SilkS" user "Ref Des/Silkscreen Top")
		(7 "B.SilkS" user "Ref Des/Silkscreen Bottom")
		(1 "F.Mask" user "Board Geometry/Soldermask Top")
		(3 "B.Mask" user "Board Geometry/Soldermask Bottom")
		(17 "Dwgs.User" user "User.Drawings")
		(19 "Cmts.User" user "User.Comments")
		(21 "Eco1.User" user "User.Eco1")
		(23 "Eco2.User" user "User.Eco2")
		(25 "Edge.Cuts" user "Board Geometry/Outline")
		(27 "Margin" user)
		(31 "F.CrtYd" user "Package Geometry/Place Bound Top")
		(29 "B.CrtYd" user "Package Geometry/Place Bound Bottom")
		(35 "F.Fab" user "Ref Des/Assembly Top")
		(33 "B.Fab" user "Ref Des/Assembly Bottom")
	)
	(footprint ""
		(layer "F.Cu")
		(at 20.32 -26.67 180)
		(property "Reference" "R388"
			(at -3.429 -0.67437 0)
			(unlocked yes)
			(layer "F.SilkS")
			(effects
				(font
					(size 0.7874 0.5842)
					(thickness 0.1524)
				)
			)
		)
		(property "Value" "VAL*"
			(at 0.02032 2.13233 180)
			(unlocked yes)
			(layer "F.Fab")
			(hide yes)
			(effects
				(font
					(size 0.7874 0.5842)
					(thickness 0.1524)
				)
			)
		)
		(property "Tolerance" "TOL*"
			(at 0.044704 3.05435 180)
			(unlocked yes)
			(layer "Cmts.User")
			(hide yes)
			(effects
				(font
					(size 0.7874 0.5842)
					(thickness 0.1524)
				)
			)
		)
		(property "User Part Number" "PARTNUM*"
			(at 0.02032 4.024884 180)
			(unlocked yes)
			(layer "Cmts.User")
			(hide yes)
			(effects
				(font
					(size 0.7874 0.5842)
					(thickness 0.1524)
				)
			)
		)
		(property "Device Type" "RESISTOR-G155-133R0-01,33OHM,1%"
			(at 0.008382 1.210564 180)
			(unlocked yes)
			(layer "F.Fab")
			(hide yes)
			(effects
				(font
					(size 0.7874 0.5842)
					(thickness 0.1524)
				)
			)
		)
		(duplicate_pad_numbers_are_jumpers no)
		(fp_line
			(start 1.143 0.5588)
			(end 1.143 -0.5588)
			(stroke
				(width 0.1)
				(type default)
			)
			(layer "F.SilkS")
		)
		(fp_line
			(start 1.143 -0.5588)
			(end -1.143 -0.5588)
			(stroke
				(width 0.1)
				(type default)
			)
			(layer "F.SilkS")
		)
		(fp_line
			(start -1.143 0.5588)
			(end 1.143 0.5588)
			(stroke
				(width 0.1)
				(type default)
			)
			(layer "F.SilkS")
		)
		(fp_line
			(start -1.143 -0.5588)
			(end -1.143 0.5588)
			(stroke
				(width 0.1)
				(type default)
			)
			(layer "F.SilkS")
		)
		(fp_rect
			(start -1.143 -0.5588)
			(end 1.143 0.5588)
			(stroke
				(width 0)
				(type default)
			)
			(fill no)
			(layer "F.CrtYd")
		)
		(fp_line
			(start 0.508 0.3048)
			(end 0.508 -0.3048)
			(stroke
				(width 0.1)
				(type default)
			)
			(layer "F.Fab")
		)
		(fp_line
			(start 0.508 -0.3048)
			(end -0.508 -0.3048)
			(stroke
				(width 0.1)
				(type default)
			)
			(layer "F.Fab")
		)
		(fp_line
			(start -0.508 0.3048)
			(end 0.508 0.3048)
			(stroke
				(width 0.1)
				(type default)
			)
			(layer "F.Fab")
		)
		(fp_line
			(start -0.508 -0.3048)
			(end -0.508 0.3048)
			(stroke
				(width 0.1)
				(type default)
			)
			(layer "F.Fab")
		)
		(pad "1" smd rect
			(at -0.5334 0 180)
			(size 0.7112 0.6096)
			(layers "F.Cu" "F.Mask" "F.Paste")
			(net "SMA2_LED_BLUE_N")
		)
		(pad "2" smd rect
			(at 0.5334 0 180)
			(size 0.7112 0.6096)
			(layers "F.Cu" "F.Mask" "F.Paste")
			(net "UNNAMED_14_LED4PV14_I266_1")
		)
		(zone
			(layer "F.Cu")
			(hatch none 0.5)
			(connect_pads
				(clearance 0)
			)
			(min_thickness 0.25)
			(keepout
				(tracks not_allowed)
				(vias allowed)
				(pads allowed)
				(copperpour not_allowed)
				(footprints allowed)
			)
			(placement
				(enabled no)
				(sheetname "")
			)
			(fill
				(thermal_gap 0.5)
				(thermal_bridge_width 0.5)
				(island_removal_mode 0)
			)
			(polygon
				(pts
					(xy 20.3962 -26.3652) (xy 20.3962 -26.9748) (xy 20.2438 -26.9748) (xy 20.2438 -26.3652)
				)
			)
		)
		(zone
			(layer "F.Cu")
			(hatch none 0.5)
			(connect_pads
				(clearance 0)
			)
			(min_thickness 0.25)
			(keepout
				(tracks allowed)
				(vias not_allowed)
				(pads allowed)
				(copperpour not_allowed)
				(footprints allowed)
			)
			(placement
				(enabled no)
				(sheetname "")
			)
			(fill
				(thermal_gap 0.5)
				(thermal_bridge_width 0.5)
				(island_removal_mode 0)
			)
			(polygon
				(pts
					(xy 20.3962 -26.3652) (xy 20.3962 -26.9748) (xy 20.2438 -26.9748) (xy 20.2438 -26.3652)
				)
			)
		)
	)
	(footprint ""
		(layer "F.Cu")
		(at 162.56 -24.511 180)
		(property "Reference" "R410"
			(at -0.508 -1.56337 0)
			(unlocked yes)
			(layer "F.SilkS")
			(effects
				(font
					(size 0.7874 0.5842)
					(thickness 0.1524)
				)
			)
		)
		(property "Value" "VAL*"
			(at 0.02032 2.13233 180)
			(unlocked yes)
			(layer "F.Fab")
			(hide yes)
			(effects
				(font
					(size 0.7874 0.5842)
					(thickness 0.1524)
				)
			)
		)
		(property "Tolerance" "TOL*"
			(at 0.044704 3.05435 180)
			(unlocked yes)
			(layer "Cmts.User")
			(hide yes)
			(effects
				(font
					(size 0.7874 0.5842)
					(thickness 0.1524)
				)
			)
		)
		(property "User Part Number" "PARTNUM*"
			(at 0.02032 4.024884 180)
			(unlocked yes)
			(layer "Cmts.User")
			(hide yes)
			(effects
				(font
					(size 0.7874 0.5842)
					(thickness 0.1524)
				)
			)
		)
		(property "Device Type" "RESISTOR-G155-14701-01,4.7KOHMA"
			(at 0.008382 1.210564 180)
			(unlocked yes)
			(layer "F.Fab")
			(hide yes)
			(effects
				(font
					(size 0.7874 0.5842)
					(thickness 0.1524)
				)
			)
		)
		(duplicate_pad_numbers_are_jumpers no)
		(fp_line
			(start 1.143 0.5588)
			(end 1.143 -0.5588)
			(stroke
				(width 0.1)
				(type default)
			)
			(layer "F.SilkS")
		)
		(fp_line
			(start 1.143 -0.5588)
			(end -1.143 -0.5588)
			(stroke
				(width 0.1)
				(type default)
			)
			(layer "F.SilkS")
		)
		(fp_line
			(start -1.143 0.5588)
			(end 1.143 0.5588)
			(stroke
				(width 0.1)
				(type default)
			)
			(layer "F.SilkS")
		)
		(fp_line
			(start -1.143 -0.5588)
			(end -1.143 0.5588)
			(stroke
				(width 0.1)
				(type default)
			)
			(layer "F.SilkS")
		)
		(fp_rect
			(start 1.143 0.5588)
			(end -1.143 -0.5588)
			(stroke
				(width 0)
				(type default)
			)
			(fill no)
			(layer "F.CrtYd")
		)
		(fp_line
			(start 0.508 0.3048)
			(end 0.508 -0.3048)
			(stroke
				(width 0.1)
				(type default)
			)
			(layer "F.Fab")
		)
		(fp_line
			(start 0.508 -0.3048)
			(end -0.508 -0.3048)
			(stroke
				(width 0.1)
				(type default)
			)
			(layer "F.Fab")
		)
		(fp_line
			(start -0.508 0.3048)
			(end 0.508 0.3048)
			(stroke
				(width 0.1)
				(type default)
			)
			(layer "F.Fab")
		)
		(fp_line
			(start -0.508 -0.3048)
			(end -0.508 0.3048)
			(stroke
				(width 0.1)
				(type default)
			)
			(layer "F.Fab")
		)
		(pad "1" smd rect
			(at -0.5334 0 180)
			(size 0.7112 0.6096)
			(layers "F.Cu" "F.Mask" "F.Paste")
			(net "XP3R3V_FPGA")
		)
		(pad "2" smd rect
			(at 0.5334 0 180)
			(size 0.7112 0.6096)
			(layers "F.Cu" "F.Mask" "F.Paste")
			(net "UNNAMED_6_LM75BDPTSSOP8_I81_A2")
		)
		(zone
			(layer "F.Cu")
			(hatch none 0.5)
			(connect_pads
				(clearance 0)
			)
			(min_thickness 0.25)
			(keepout
				(tracks allowed)
				(vias not_allowed)
				(pads allowed)
				(copperpour not_allowed)
				(footprints allowed)
			)
			(placement
				(enabled no)
				(sheetname "")
			)
			(fill
				(thermal_gap 0.5)
				(thermal_bridge_width 0.5)
				(island_removal_mode 0)
			)
			(polygon
				(pts
					(xy 162.4838 -24.8158) (xy 162.4838 -24.2062) (xy 162.6362 -24.2062) (xy 162.6362 -24.8158)
				)
			)
		)
		(zone
			(layer "F.Cu")
			(hatch none 0.5)
			(connect_pads
				(clearance 0)
			)
			(min_thickness 0.25)
			(keepout
				(tracks not_allowed)
				(vias allowed)
				(pads allowed)
				(copperpour not_allowed)
				(footprints allowed)
			)
			(placement
				(enabled no)
				(sheetname "")
			)
			(fill
				(thermal_gap 0.5)
				(thermal_bridge_width 0.5)
				(island_removal_mode 0)
			)
			(polygon
				(pts
					(xy 162.4838 -24.8158) (xy 162.4838 -24.2062) (xy 162.6362 -24.2062) (xy 162.6362 -24.8158)
				)
			)
		)
	)
)
